(kicad_pcb
	(version 20260206)
	(generator "pcbnew")
	(generator_version "10.0")
	(general
		(thickness 1.6)
		(legacy_teardrops no)
	)
	(paper "A4")
	(title_block
		(title "peb — Lightning_PEB_BRD.brd")
		(comment 1 "Lightning (Wiwynn / Facebook NVMe JBOF) / footprints 1752-1758 of 2563")
	)
	(layers
		(0 "F.Cu" signal "TOP")
		(4 "In1.Cu" signal "L2GND")
		(6 "In2.Cu" signal "L3")
		(8 "In3.Cu" signal "L4VCC")
		(10 "In4.Cu" signal "L5VCC")
		(12 "In5.Cu" signal "L6")
		(14 "In6.Cu" signal "L7GND")
		(2 "B.Cu" signal "BOTTOM")
		(9 "F.Adhes" user "F.Adhesive")
		(11 "B.Adhes" user "B.Adhesive")
		(13 "F.Paste" user "Package Geometry/Pastemask Top")
		(15 "B.Paste" user "Package Geometry/Pastemask Bottom")
		(5 "F.SilkS" user "Ref Des/Silkscreen Top")
		(7 "B.SilkS" user "Ref Des/Silkscreen Bottom")
		(1 "F.Mask" user "Board Geometry/Soldermask Top")
		(3 "B.Mask" user "Board Geometry/Soldermask Bottom")
		(17 "Dwgs.User" user "User.Drawings")
		(19 "Cmts.User" user "User.Comments")
		(21 "Eco1.User" user "User.Eco1")
		(23 "Eco2.User" user "User.Eco2")
		(25 "Edge.Cuts" user "Board Geometry/Outline")
		(27 "Margin" user)
		(31 "F.CrtYd" user "Package Geometry/Place Bound Top")
		(29 "B.CrtYd" user "Package Geometry/Place Bound Bottom")
		(35 "F.Fab" user "Ref Des/Assembly Top")
		(33 "B.Fab" user "Ref Des/Assembly Bottom")
	)
	(footprint ""
		(layer "B.Cu")
		(at 158.512002 -59.209432 90)
		(property "Reference" "PC200"
			(at 0 0 90)
			(layer "B.SilkS")
			(hide yes)
			(effects
				(font
					(size 1.27 1.27)
				)
				(justify mirror)
			)
		)
		(property "Value" "SCD1U50V3KX-GP"
			(at 0 -2.8194 90)
			(unlocked yes)
			(layer "B.Fab")
			(hide yes)
			(effects
				(font
					(size 1.016 1.016)
					(thickness 0.1524)
				)
				(justify mirror)
			)
		)
		(property "Device Type" "C603H36"
			(at 0 -4.3434 90)
			(unlocked yes)
			(layer "B.Fab")
			(hide yes)
			(effects
				(font
					(size 1.016 1.016)
					(thickness 0.1524)
				)
				(justify mirror)
			)
		)
		(duplicate_pad_numbers_are_jumpers no)
		(fp_line
			(start -0.508 0)
			(end 0.508 0)
			(stroke
				(width 0.2032)
				(type default)
			)
			(layer "B.SilkS")
		)
		(fp_rect
			(start 0.5842 1.3335)
			(end -0.5842 -1.3335)
			(stroke
				(width 0)
				(type default)
			)
			(fill no)
			(layer "B.CrtYd")
		)
		(fp_rect
			(start 0.5842 1.3335)
			(end -0.5842 -1.3335)
			(stroke
				(width 0)
				(type default)
			)
			(fill no)
			(layer "B.Fab")
		)
		(pad "1" smd custom
			(at 0 -0.762 270)
			(size 0.2159 0.2159)
			(layers "B.Cu" "B.Mask" "B.Paste")
			(net "P0V9_VBST")
			(options
				(clearance outline)
				(anchor circle)
			)
			(primitives
				(gr_poly
					(pts
						(arc
							(start -0.3302 0.4318)
							(mid -0.402042 0.402042)
							(end -0.4318 0.3302)
						)
						(arc
							(start -0.4318 -0.3302)
							(mid -0.402042 -0.402042)
							(end -0.3302 -0.4318)
						)
						(arc
							(start 0.3302 -0.4318)
							(mid 0.402042 -0.402042)
							(end 0.4318 -0.3302)
						)
						(arc
							(start 0.4318 0.3302)
							(mid 0.402042 0.402042)
							(end 0.3302 0.4318)
						)
					)
					(width 0)
					(fill yes)
				)
			)
		)
		(pad "2" smd custom
			(at 0 0.762 270)
			(size 0.2159 0.2159)
			(layers "B.Cu" "B.Mask" "B.Paste")
			(net "P0V9_VBST_RC")
			(options
				(clearance outline)
				(anchor circle)
			)
			(primitives
				(gr_poly
					(pts
						(arc
							(start -0.3302 0.4318)
							(mid -0.402042 0.402042)
							(end -0.4318 0.3302)
						)
						(arc
							(start -0.4318 -0.3302)
							(mid -0.402042 -0.402042)
							(end -0.3302 -0.4318)
						)
						(arc
							(start 0.3302 -0.4318)
							(mid 0.402042 -0.402042)
							(end 0.4318 -0.3302)
						)
						(arc
							(start 0.4318 0.3302)
							(mid 0.402042 0.402042)
							(end 0.3302 0.4318)
						)
					)
					(width 0)
					(fill yes)
				)
			)
		)
	)
	(footprint ""
		(layer "B.Cu")
		(at 218.5416 -4.1148 90)
		(property "Reference" "Q3202"
			(at 0 0 90)
			(layer "B.SilkS")
			(hide yes)
			(effects
				(font
					(size 1.27 1.27)
				)
				(justify mirror)
			)
		)
		(property "Value" "2N7002K-1-GP"
			(at -0.127 -8.9662 90)
			(unlocked yes)
			(layer "B.Fab")
			(hide yes)
			(effects
				(font
					(size 1.016 1.016)
					(thickness 0.1524)
				)
				(justify mirror)
			)
		)
		(property "Device Type" "SOT23DGS2D4H44"
			(at -0.127 -10.4902 90)
			(unlocked yes)
			(layer "B.Fab")
			(hide yes)
			(effects
				(font
					(size 1.016 1.016)
					(thickness 0.1524)
				)
				(justify mirror)
			)
		)
		(duplicate_pad_numbers_are_jumpers no)
		(fp_line
			(start 1.651 -1.778)
			(end 1.651 1.778)
			(stroke
				(width 0.1524)
				(type default)
			)
			(layer "B.SilkS")
		)
		(fp_line
			(start -1.651 -1.778)
			(end 1.651 -1.778)
			(stroke
				(width 0.1524)
				(type default)
			)
			(layer "B.SilkS")
		)
		(fp_line
			(start 1.651 1.778)
			(end -1.651 1.778)
			(stroke
				(width 0.1524)
				(type default)
			)
			(layer "B.SilkS")
		)
		(fp_line
			(start -1.651 1.778)
			(end -1.651 -1.778)
			(stroke
				(width 0.1524)
				(type default)
			)
			(layer "B.SilkS")
		)
		(fp_poly
			(pts
				(xy 1.778 1.8796) (xy 1.778 -1.8796) (xy -1.778 -1.8796) (xy -1.778 1.8796)
			)
			(stroke
				(width 0)
				(type default)
			)
			(fill no)
			(layer "B.CrtYd")
		)
		(fp_poly
			(pts
				(xy 1.778 1.8796) (xy 1.778 -1.8796) (xy -1.778 -1.8796) (xy -1.778 1.8796)
			)
			(stroke
				(width 0)
				(type default)
			)
			(fill no)
			(layer "B.Fab")
		)
		(pad "D" smd custom
			(at 0 -0.9525 270)
			(size 0.1905 0.1905)
			(layers "B.Cu" "B.Mask" "B.Paste")
			(net "Q3202_D")
			(options
				(clearance outline)
				(anchor circle)
			)
			(primitives
				(gr_poly
					(pts
						(arc
							(start -0.1778 -0.5715)
							(mid -0.321484 -0.511984)
							(end -0.381 -0.3683)
						)
						(arc
							(start -0.381 0.3683)
							(mid -0.321484 0.511984)
							(end -0.1778 0.5715)
						)
						(arc
							(start 0.1778 0.5715)
							(mid 0.321484 0.511984)
							(end 0.381 0.3683)
						)
						(arc
							(start 0.381 -0.3683)
							(mid 0.321484 -0.511984)
							(end 0.1778 -0.5715)
						)
					)
					(width 0)
					(fill yes)
				)
			)
		)
		(pad "G" smd custom
			(at 0.98425 0.9525 270)
			(size 0.1905 0.1905)
			(layers "B.Cu" "B.Mask" "B.Paste")
			(net "P3V3_STBY")
			(options
				(clearance outline)
				(anchor circle)
			)
			(primitives
				(gr_poly
					(pts
						(arc
							(start -0.1778 -0.5715)
							(mid -0.321484 -0.511984)
							(end -0.381 -0.3683)
						)
						(arc
							(start -0.381 0.3683)
							(mid -0.321484 0.511984)
							(end -0.1778 0.5715)
						)
						(arc
							(start 0.1778 0.5715)
							(mid 0.321484 0.511984)
							(end 0.381 0.3683)
						)
						(arc
							(start 0.381 -0.3683)
							(mid 0.321484 -0.511984)
							(end 0.1778 -0.5715)
						)
					)
					(width 0)
					(fill yes)
				)
			)
		)
		(pad "S" smd custom
			(at -0.98425 0.9525 270)
			(size 0.1905 0.1905)
			(layers "B.Cu" "B.Mask" "B.Paste")
			(net "GND")
			(options
				(clearance outline)
				(anchor circle)
			)
			(primitives
				(gr_poly
					(pts
						(arc
							(start -0.1778 -0.5715)
							(mid -0.321484 -0.511984)
							(end -0.381 -0.3683)
						)
						(arc
							(start -0.381 0.3683)
							(mid -0.321484 0.511984)
							(end -0.1778 0.5715)
						)
						(arc
							(start 0.1778 0.5715)
							(mid 0.321484 0.511984)
							(end 0.381 0.3683)
						)
						(arc
							(start 0.381 -0.3683)
							(mid 0.321484 -0.511984)
							(end 0.1778 -0.5715)
						)
					)
					(width 0)
					(fill yes)
				)
			)
		)
	)
	(footprint ""
		(layer "B.Cu")
		(at 226.822 -23.241 180)
		(property "Reference" "R828"
			(at 0 0 0)
			(layer "B.SilkS")
			(hide yes)
			(effects
				(font
					(size 1.27 1.27)
				)
				(justify mirror)
			)
		)
		(property "Value" "0R2J-2-GP"
			(at -0.064008 -3.993896 180)
			(unlocked yes)
			(layer "B.Fab")
			(hide yes)
			(effects
				(font
					(size 1.016 1.016)
					(thickness 0.1524)
				)
				(justify mirror)
			)
		)
		(property "Device Type" "R402H16"
			(at -0.064008 -5.517896 180)
			(unlocked yes)
			(layer "B.Fab")
			(hide yes)
			(effects
				(font
					(size 1.016 1.016)
					(thickness 0.1524)
				)
				(justify mirror)
			)
		)
		(duplicate_pad_numbers_are_jumpers no)
		(fp_line
			(start 0.508 -0.9398)
			(end 0.508 0.9398)
			(stroke
				(width 0.1524)
				(type default)
			)
			(layer "B.SilkS")
		)
		(fp_line
			(start -0.508 -0.9398)
			(end 0.508 -0.9398)
			(stroke
				(width 0.1524)
				(type default)
			)
			(layer "B.SilkS")
		)
		(fp_rect
			(start 0.508 0.9398)
			(end -0.508 -0.9398)
			(stroke
				(width 0)
				(type default)
			)
			(fill no)
			(layer "B.CrtYd")
		)
		(fp_rect
			(start 0.508 0.9398)
			(end -0.508 -0.9398)
			(stroke
				(width 0)
				(type default)
			)
			(fill no)
			(layer "B.Fab")
		)
		(pad "1" smd custom
			(at 0 -0.4445)
			(size 0.1397 0.1397)
			(layers "B.Cu" "B.Mask" "B.Paste")
			(net "HOST4_RST_N_LS")
			(options
				(clearance outline)
				(anchor circle)
			)
			(primitives
				(gr_poly
					(pts
						(arc
							(start -0.1778 0.2794)
							(mid -0.249642 0.249642)
							(end -0.2794 0.1778)
						)
						(arc
							(start -0.2794 -0.1778)
							(mid -0.249642 -0.249642)
							(end -0.1778 -0.2794)
						)
						(arc
							(start 0.1778 -0.2794)
							(mid 0.249642 -0.249642)
							(end 0.2794 -0.1778)
						)
						(arc
							(start 0.2794 0.1778)
							(mid 0.249642 0.249642)
							(end 0.1778 0.2794)
						)
					)
					(width 0)
					(fill yes)
				)
			)
		)
		(pad "2" smd custom
			(at 0 0.4445)
			(size 0.1397 0.1397)
			(layers "B.Cu" "B.Mask" "B.Paste")
			(net "LBI_ADDR_3_R")
			(options
				(clearance outline)
				(anchor circle)
			)
			(primitives
				(gr_poly
					(pts
						(arc
							(start -0.1778 0.2794)
							(mid -0.249642 0.249642)
							(end -0.2794 0.1778)
						)
						(arc
							(start -0.2794 -0.1778)
							(mid -0.249642 -0.249642)
							(end -0.1778 -0.2794)
						)
						(arc
							(start 0.1778 -0.2794)
							(mid 0.249642 -0.249642)
							(end 0.2794 -0.1778)
						)
						(arc
							(start 0.2794 0.1778)
							(mid 0.249642 0.249642)
							(end 0.1778 0.2794)
						)
					)
					(width 0)
					(fill yes)
				)
			)
		)
	)
	(footprint ""
		(layer "B.Cu")
		(at 228.6254 -49.991772 90)
		(property "Reference" "C577"
			(at 0 0 90)
			(layer "B.SilkS")
			(hide yes)
			(effects
				(font
					(size 1.27 1.27)
				)
				(justify mirror)
			)
		)
		(property "Value" "SCD1U16V1KX-1-GP"
			(at 2.8321 -1.7399 90)
			(unlocked yes)
			(layer "B.Fab")
			(hide yes)
			(effects
				(font
					(size 1.016 1.016)
					(thickness 0.1524)
				)
				(justify mirror)
			)
		)
		(property "Device Type" "C0201H13"
			(at 2.8321 -3.2639 90)
			(unlocked yes)
			(layer "B.Fab")
			(hide yes)
			(effects
				(font
					(size 1.016 1.016)
					(thickness 0.1524)
				)
				(justify mirror)
			)
		)
		(duplicate_pad_numbers_are_jumpers no)
		(fp_rect
			(start 0.2794 0.6477)
			(end -0.2794 -0.6477)
			(stroke
				(width 0)
				(type default)
			)
			(fill no)
			(layer "B.CrtYd")
		)
		(fp_rect
			(start 0.2794 0.6477)
			(end -0.2794 -0.6477)
			(stroke
				(width 0)
				(type default)
			)
			(fill no)
			(layer "B.Fab")
		)
		(pad "1" smd custom
			(at 0 -0.2794 270)
			(size 0.0762 0.0762)
			(layers "B.Cu" "B.Mask" "B.Paste")
			(net "DUT_AVD_PCIE")
			(options
				(clearance outline)
				(anchor circle)
			)
			(primitives
				(gr_poly
					(pts
						(arc
							(start 0.1524 0.127)
							(mid 0.137521 0.162921)
							(end 0.1016 0.1778)
						)
						(arc
							(start -0.1016 0.1778)
							(mid -0.137521 0.162921)
							(end -0.1524 0.127)
						)
						(arc
							(start -0.1524 -0.127)
							(mid -0.137521 -0.162921)
							(end -0.1016 -0.1778)
						)
						(arc
							(start 0.1016 -0.1778)
							(mid 0.137521 -0.162921)
							(end 0.1524 -0.127)
						)
					)
					(width 0)
					(fill yes)
				)
			)
		)
		(pad "2" smd custom
			(at 0 0.2794 270)
			(size 0.0762 0.0762)
			(layers "B.Cu" "B.Mask" "B.Paste")
			(net "GND")
			(options
				(clearance outline)
				(anchor circle)
			)
			(primitives
				(gr_poly
					(pts
						(arc
							(start 0.1524 0.127)
							(mid 0.137521 0.162921)
							(end 0.1016 0.1778)
						)
						(arc
							(start -0.1016 0.1778)
							(mid -0.137521 0.162921)
							(end -0.1524 0.127)
						)
						(arc
							(start -0.1524 -0.127)
							(mid -0.137521 -0.162921)
							(end -0.1016 -0.1778)
						)
						(arc
							(start 0.1016 -0.1778)
							(mid 0.137521 -0.162921)
							(end 0.1524 -0.127)
						)
					)
					(width 0)
					(fill yes)
				)
			)
		)
	)
	(footprint ""
		(layer "B.Cu")
		(at 225.883724 -190.601092)
		(property "Reference" "R4143"
			(at 0 0 0)
			(layer "B.SilkS")
			(hide yes)
			(effects
				(font
					(size 1.27 1.27)
				)
				(justify mirror)
			)
		)
		(property "Value" "4K7R2F-GP"
			(at -0.064008 -3.993896 0)
			(unlocked yes)
			(layer "B.Fab")
			(hide yes)
			(effects
				(font
					(size 1.016 1.016)
					(thickness 0.1524)
				)
				(justify mirror)
			)
		)
		(property "Device Type" "R402H16"
			(at -0.064008 -5.517896 0)
			(unlocked yes)
			(layer "B.Fab")
			(hide yes)
			(effects
				(font
					(size 1.016 1.016)
					(thickness 0.1524)
				)
				(justify mirror)
			)
		)
		(duplicate_pad_numbers_are_jumpers no)
		(fp_line
			(start -0.508 -0.9398)
			(end 0.508 -0.9398)
			(stroke
				(width 0.1524)
				(type default)
			)
			(layer "B.SilkS")
		)
		(fp_line
			(start 0.508 -0.9398)
			(end 0.508 0.9398)
			(stroke
				(width 0.1524)
				(type default)
			)
			(layer "B.SilkS")
		)
		(fp_rect
			(start 0.508 0.9398)
			(end -0.508 -0.9398)
			(stroke
				(width 0)
				(type default)
			)
			(fill no)
			(layer "B.CrtYd")
		)
		(fp_rect
			(start 0.508 0.9398)
			(end -0.508 -0.9398)
			(stroke
				(width 0)
				(type default)
			)
			(fill no)
			(layer "B.Fab")
		)
		(pad "1" smd custom
			(at 0 -0.4445 180)
			(size 0.1397 0.1397)
			(layers "B.Cu" "B.Mask" "B.Paste")
			(net "SSD_ATNLED#8")
			(options
				(clearance outline)
				(anchor circle)
			)
			(primitives
				(gr_poly
					(pts
						(arc
							(start -0.1778 0.2794)
							(mid -0.249642 0.249642)
							(end -0.2794 0.1778)
						)
						(arc
							(start -0.2794 -0.1778)
							(mid -0.249642 -0.249642)
							(end -0.1778 -0.2794)
						)
						(arc
							(start 0.1778 -0.2794)
							(mid 0.249642 -0.249642)
							(end 0.2794 -0.1778)
						)
						(arc
							(start 0.2794 0.1778)
							(mid 0.249642 0.249642)
							(end 0.1778 0.2794)
						)
					)
					(width 0)
					(fill yes)
				)
			)
		)
		(pad "2" smd custom
			(at 0 0.4445 180)
			(size 0.1397 0.1397)
			(layers "B.Cu" "B.Mask" "B.Paste")
			(net "P3V3_STBY")
			(options
				(clearance outline)
				(anchor circle)
			)
			(primitives
				(gr_poly
					(pts
						(arc
							(start -0.1778 0.2794)
							(mid -0.249642 0.249642)
							(end -0.2794 0.1778)
						)
						(arc
							(start -0.2794 -0.1778)
							(mid -0.249642 -0.249642)
							(end -0.1778 -0.2794)
						)
						(arc
							(start 0.1778 -0.2794)
							(mid 0.249642 -0.249642)
							(end 0.2794 -0.1778)
						)
						(arc
							(start 0.2794 0.1778)
							(mid 0.249642 0.249642)
							(end 0.1778 0.2794)
						)
					)
					(width 0)
					(fill yes)
				)
			)
		)
	)
	(footprint ""
		(layer "B.Cu")
		(at 253.5936 -36.009072 90)
		(property "Reference" "C555"
			(at 0 0 90)
			(layer "B.SilkS")
			(hide yes)
			(effects
				(font
					(size 1.27 1.27)
				)
				(justify mirror)
			)
		)
		(property "Value" "SCD1U16V1KX-1-GP"
			(at 2.8321 -1.7399 90)
			(unlocked yes)
			(layer "B.Fab")
			(hide yes)
			(effects
				(font
					(size 1.016 1.016)
					(thickness 0.1524)
				)
				(justify mirror)
			)
		)
		(property "Device Type" "C0201H13"
			(at 2.8321 -3.2639 90)
			(unlocked yes)
			(layer "B.Fab")
			(hide yes)
			(effects
				(font
					(size 1.016 1.016)
					(thickness 0.1524)
				)
				(justify mirror)
			)
		)
		(duplicate_pad_numbers_are_jumpers no)
		(fp_rect
			(start 0.2794 0.6477)
			(end -0.2794 -0.6477)
			(stroke
				(width 0)
				(type default)
			)
			(fill no)
			(layer "B.CrtYd")
		)
		(fp_rect
			(start 0.2794 0.6477)
			(end -0.2794 -0.6477)
			(stroke
				(width 0)
				(type default)
			)
			(fill no)
			(layer "B.Fab")
		)
		(pad "1" smd custom
			(at 0 -0.2794 270)
			(size 0.0762 0.0762)
			(layers "B.Cu" "B.Mask" "B.Paste")
			(net "DUT_AVD_PCIE")
			(options
				(clearance outline)
				(anchor circle)
			)
			(primitives
				(gr_poly
					(pts
						(arc
							(start 0.1524 0.127)
							(mid 0.137521 0.162921)
							(end 0.1016 0.1778)
						)
						(arc
							(start -0.1016 0.1778)
							(mid -0.137521 0.162921)
							(end -0.1524 0.127)
						)
						(arc
							(start -0.1524 -0.127)
							(mid -0.137521 -0.162921)
							(end -0.1016 -0.1778)
						)
						(arc
							(start 0.1016 -0.1778)
							(mid 0.137521 -0.162921)
							(end 0.1524 -0.127)
						)
					)
					(width 0)
					(fill yes)
				)
			)
		)
		(pad "2" smd custom
			(at 0 0.2794 270)
			(size 0.0762 0.0762)
			(layers "B.Cu" "B.Mask" "B.Paste")
			(net "GND")
			(options
				(clearance outline)
				(anchor circle)
			)
			(primitives
				(gr_poly
					(pts
						(arc
							(start 0.1524 0.127)
							(mid 0.137521 0.162921)
							(end 0.1016 0.1778)
						)
						(arc
							(start -0.1016 0.1778)
							(mid -0.137521 0.162921)
							(end -0.1524 0.127)
						)
						(arc
							(start -0.1524 -0.127)
							(mid -0.137521 -0.162921)
							(end -0.1016 -0.1778)
						)
						(arc
							(start 0.1016 -0.1778)
							(mid 0.137521 -0.162921)
							(end 0.1524 -0.127)
						)
					)
					(width 0)
					(fill yes)
				)
			)
		)
	)
	(footprint ""
		(layer "B.Cu")
		(at 221.234 -20.447 180)
		(property "Reference" "R710"
			(at 0 0 0)
			(layer "B.SilkS")
			(hide yes)
			(effects
				(font
					(size 1.27 1.27)
				)
				(justify mirror)
			)
		)
		(property "Value" "1KR2F-3-GP"
			(at -0.064008 -3.993896 180)
			(unlocked yes)
			(layer "B.Fab")
			(hide yes)
			(effects
				(font
					(size 1.016 1.016)
					(thickness 0.1524)
				)
				(justify mirror)
			)
		)
		(property "Device Type" "R402H16"
			(at -0.064008 -5.517896 180)
			(unlocked yes)
			(layer "B.Fab")
			(hide yes)
			(effects
				(font
					(size 1.016 1.016)
					(thickness 0.1524)
				)
				(justify mirror)
			)
		)
		(duplicate_pad_numbers_are_jumpers no)
		(fp_line
			(start 0.508 -0.9398)
			(end 0.508 0.9398)
			(stroke
				(width 0.1524)
				(type default)
			)
			(layer "B.SilkS")
		)
		(fp_line
			(start -0.508 -0.9398)
			(end 0.508 -0.9398)
			(stroke
				(width 0.1524)
				(type default)
			)
			(layer "B.SilkS")
		)
		(fp_rect
			(start 0.508 0.9398)
			(end -0.508 -0.9398)
			(stroke
				(width 0)
				(type default)
			)
			(fill no)
			(layer "B.CrtYd")
		)
		(fp_rect
			(start 0.508 0.9398)
			(end -0.508 -0.9398)
			(stroke
				(width 0)
				(type default)
			)
			(fill no)
			(layer "B.Fab")
		)
		(pad "1" smd custom
			(at 0 -0.4445)
			(size 0.1397 0.1397)
			(layers "B.Cu" "B.Mask" "B.Paste")
			(net "DUT_VDDO")
			(options
				(clearance outline)
				(anchor circle)
			)
			(primitives
				(gr_poly
					(pts
						(arc
							(start -0.1778 0.2794)
							(mid -0.249642 0.249642)
							(end -0.2794 0.1778)
						)
						(arc
							(start -0.2794 -0.1778)
							(mid -0.249642 -0.249642)
							(end -0.1778 -0.2794)
						)
						(arc
							(start 0.1778 -0.2794)
							(mid 0.249642 -0.249642)
							(end 0.2794 -0.1778)
						)
						(arc
							(start 0.2794 0.1778)
							(mid 0.249642 0.249642)
							(end 0.1778 0.2794)
						)
					)
					(width 0)
					(fill yes)
				)
			)
		)
		(pad "2" smd custom
			(at 0 0.4445)
			(size 0.1397 0.1397)
			(layers "B.Cu" "B.Mask" "B.Paste")
			(net "MDIO")
			(options
				(clearance outline)
				(anchor circle)
			)
			(primitives
				(gr_poly
					(pts
						(arc
							(start -0.1778 0.2794)
							(mid -0.249642 0.249642)
							(end -0.2794 0.1778)
						)
						(arc
							(start -0.2794 -0.1778)
							(mid -0.249642 -0.249642)
							(end -0.1778 -0.2794)
						)
						(arc
							(start 0.1778 -0.2794)
							(mid 0.249642 -0.249642)
							(end 0.2794 -0.1778)
						)
						(arc
							(start 0.2794 0.1778)
							(mid 0.249642 0.249642)
							(end 0.1778 0.2794)
						)
					)
					(width 0)
					(fill yes)
				)
			)
		)
	)
)
